(kicad_pcb
	(version 20241229)
	(generator "pcbnew")
	(generator_version "9.0")
	(general
		(thickness 1.62)
		(legacy_teardrops no)
	)
	(paper "A3")
	(title_block
		(title "COM Express 7 Baseboard")
		(date "2025-02-04")
		(rev "1.1.2")
		(company "Antmicro Ltd")
		(comment 1 "www.antmicro.com")
		(comment 9 "footprints 113-115 of 802")
	)
	(layers
		(0 "F.Cu" signal)
		(4 "In1.Cu" signal)
		(6 "In2.Cu" signal)
		(8 "In3.Cu" signal)
		(10 "In4.Cu" signal)
		(12 "In5.Cu" signal)
		(14 "In6.Cu" signal)
		(2 "B.Cu" signal)
		(9 "F.Adhes" user "F.Adhesive")
		(11 "B.Adhes" user "B.Adhesive")
		(13 "F.Paste" user)
		(15 "B.Paste" user)
		(5 "F.SilkS" user "F.Silkscreen")
		(7 "B.SilkS" user "B.Silkscreen")
		(1 "F.Mask" user)
		(3 "B.Mask" user)
		(17 "Dwgs.User" user "User.Drawings")
		(19 "Cmts.User" user "User.Comments")
		(21 "Eco1.User" user "User.Eco1")
		(23 "Eco2.User" user "User.Eco2")
		(25 "Edge.Cuts" user)
		(27 "Margin" user)
		(31 "F.CrtYd" user "F.Courtyard")
		(29 "B.CrtYd" user "B.Courtyard")
		(35 "F.Fab" user)
		(33 "B.Fab" user)
	)
	(footprint "antmicro-footprints:QSOP-24_8.65x6mm_P0.635mm"
		(layer "F.Cu")
		(at 257.34 86.05 180)
		(property "Reference" "U24"
			(at -1.16 -5.52 0)
			(layer "F.SilkS")
			(effects
				(font
					(size 0.7 0.7)
					(thickness 0.15)
				)
				(justify right bottom)
			)
		)
		(property "Value" "ADT7476AARQZ"
			(at 0 2 90)
			(layer "F.Fab")
			(effects
				(font
					(size 0.7 0.7)
					(thickness 0.15)
				)
				(justify left bottom)
			)
		)
		(property "Datasheet" "https://www.onsemi.com/pdf/datasheet/adt7476a-d.pdf"
			(at 0 0 180)
			(layer "F.Fab")
			(hide yes)
			(effects
				(font
					(size 1.27 1.27)
					(thickness 0.15)
				)
			)
		)
		(property "Author" "Antmicro"
			(at 514.68 172.1 0)
			(layer "F.Fab")
			(hide yes)
			(effects
				(font
					(size 1 1)
					(thickness 0.15)
				)
			)
		)
		(property "License" "Apache-2.0"
			(at 514.68 172.1 0)
			(layer "F.Fab")
			(hide yes)
			(effects
				(font
					(size 1 1)
					(thickness 0.15)
				)
			)
		)
		(property "MPN" "ADT7476AARQZ"
			(at 514.68 172.1 0)
			(layer "F.Fab")
			(hide yes)
			(effects
				(font
					(size 1 1)
					(thickness 0.15)
				)
			)
		)
		(property "Manufacturer" "Onsemi"
			(at 514.68 172.1 0)
			(layer "F.Fab")
			(hide yes)
			(effects
				(font
					(size 1 1)
					(thickness 0.15)
				)
			)
		)
		(sheetname "Misc")
		(sheetfile "misc.kicad_sch")
		(attr smd)
		(fp_line
			(start 1.4 4.3)
			(end -1.4 4.3)
			(stroke
				(width 0.15)
				(type solid)
			)
			(layer "F.SilkS")
		)
		(fp_line
			(start -1.6 -4.3)
			(end 1.6 -4.3)
			(stroke
				(width 0.15)
				(type solid)
			)
			(layer "F.SilkS")
		)
		(fp_circle
			(center -3.55 -3.49)
			(end -3.5 -3.49)
			(stroke
				(width 0.15)
				(type solid)
			)
			(fill yes)
			(layer "F.SilkS")
		)
		(fp_rect
			(start -3.3 -4.6)
			(end 3.3 4.6)
			(stroke
				(width 0.05)
				(type solid)
			)
			(fill no)
			(layer "F.CrtYd")
		)
		(fp_line
			(start 2 4.25)
			(end -2 4.25)
			(stroke
				(width 0.15)
				(type solid)
			)
			(layer "F.Fab")
		)
		(fp_line
			(start 2 -4.25)
			(end 2 4.25)
			(stroke
				(width 0.15)
				(type solid)
			)
			(layer "F.Fab")
		)
		(fp_line
			(start -1.25 -4.25)
			(end 2 -4.25)
			(stroke
				(width 0.15)
				(type solid)
			)
			(layer "F.Fab")
		)
		(fp_line
			(start -2 4.25)
			(end -2 -1.5)
			(stroke
				(width 0.15)
				(type solid)
			)
			(layer "F.Fab")
		)
		(fp_line
			(start -2 -1.5)
			(end -2 -3.5)
			(stroke
				(width 0.15)
				(type solid)
			)
			(layer "F.Fab")
		)
		(fp_line
			(start -2 -3.5)
			(end -1.25 -4.25)
			(stroke
				(width 0.15)
				(type solid)
			)
			(layer "F.Fab")
		)
		(pad "1" smd rect
			(at -2.64 -3.49 90)
			(size 0.42 1.12)
			(layers "F.Cu" "F.Mask" "F.Paste")
			(net 372 "/Com Express 7 MGMT/I2C.SDA")
			(pinfunction "SDA")
			(pintype "open_collector")
			(teardrops
				(best_length_ratio 0.2)
				(max_length 1)
				(best_width_ratio 0.9)
				(max_width 2)
				(curved_edges yes)
				(filter_ratio 0.9)
				(enabled yes)
				(allow_two_segments yes)
				(prefer_zone_connections yes)
			)
		)
		(pad "2" smd rect
			(at -2.64 -2.86 90)
			(size 0.42 1.12)
			(layers "F.Cu" "F.Mask" "F.Paste")
			(net 371 "/Com Express 7 MGMT/I2C.SCL")
			(pinfunction "SCL")
			(pintype "open_collector")
			(teardrops
				(best_length_ratio 0.2)
				(max_length 1)
				(best_width_ratio 0.9)
				(max_width 2)
				(curved_edges yes)
				(filter_ratio 0.9)
				(enabled yes)
				(allow_two_segments yes)
				(prefer_zone_connections yes)
			)
		)
		(pad "3" smd rect
			(at -2.64 -2.22 90)
			(size 0.42 1.12)
			(layers "F.Cu" "F.Mask" "F.Paste")
			(net 1 "GND")
			(pinfunction "GND")
			(pintype "power_in")
			(teardrops
				(best_length_ratio 0.2)
				(max_length 1)
				(best_width_ratio 0.9)
				(max_width 2)
				(curved_edges yes)
				(filter_ratio 0.9)
				(enabled yes)
				(allow_two_segments yes)
				(prefer_zone_connections yes)
			)
		)
		(pad "4" smd rect
			(at -2.64 -1.59 90)
			(size 0.42 1.12)
			(layers "F.Cu" "F.Mask" "F.Paste")
			(net 80 "Net-(Q6-D)")
			(pinfunction "VCC")
			(pintype "power_in")
			(teardrops
				(best_length_ratio 0.2)
				(max_length 1)
				(best_width_ratio 0.9)
				(max_width 2)
				(curved_edges yes)
				(filter_ratio 0.9)
				(enabled yes)
				(allow_two_segments yes)
				(prefer_zone_connections yes)
			)
		)
		(pad "5" smd rect
			(at -2.64 -0.95 90)
			(size 0.42 1.12)
			(layers "F.Cu" "F.Mask" "F.Paste")
			(net 706 "Net-(U24-GPIO0)")
			(pinfunction "GPIO0")
			(pintype "open_collector")
			(teardrops
				(best_length_ratio 0.2)
				(max_length 1)
				(best_width_ratio 0.9)
				(max_width 2)
				(curved_edges yes)
				(filter_ratio 0.9)
				(enabled yes)
				(allow_two_segments yes)
				(prefer_zone_connections yes)
			)
		)
		(pad "6" smd rect
			(at -2.64 -0.32 90)
			(size 0.42 1.12)
			(layers "F.Cu" "F.Mask" "F.Paste")
			(net 705 "Net-(U24-GPIO1)")
			(pinfunction "GPIO1")
			(pintype "open_collector")
			(teardrops
				(best_length_ratio 0.2)
				(max_length 1)
				(best_width_ratio 0.9)
				(max_width 2)
				(curved_edges yes)
				(filter_ratio 0.9)
				(enabled yes)
				(allow_two_segments yes)
				(prefer_zone_connections yes)
			)
		)
		(pad "7" smd rect
			(at -2.64 0.32 90)
			(size 0.42 1.12)
			(layers "F.Cu" "F.Mask" "F.Paste")
			(net 704 "Net-(U24-GPIO2)")
			(pinfunction "GPIO2")
			(pintype "open_collector")
			(teardrops
				(best_length_ratio 0.2)
				(max_length 1)
				(best_width_ratio 0.9)
				(max_width 2)
				(curved_edges yes)
				(filter_ratio 0.9)
				(enabled yes)
				(allow_two_segments yes)
				(prefer_zone_connections yes)
			)
		)
		(pad "8" smd rect
			(at -2.64 0.95 90)
			(size 0.42 1.12)
			(layers "F.Cu" "F.Mask" "F.Paste")
			(net 703 "Net-(U24-GPIO3)")
			(pinfunction "GPIO3")
			(pintype "open_collector")
			(teardrops
				(best_length_ratio 0.2)
				(max_length 1)
				(best_width_ratio 0.9)
				(max_width 2)
				(curved_edges yes)
				(filter_ratio 0.9)
				(enabled yes)
				(allow_two_segments yes)
				(prefer_zone_connections yes)
			)
		)
		(pad "9" smd rect
			(at -2.64 1.59 90)
			(size 0.42 1.12)
			(layers "F.Cu" "F.Mask" "F.Paste")
			(net 707 "Net-(U24-TACH3)")
			(pinfunction "TACH3")
			(pintype "input")
			(teardrops
				(best_length_ratio 0.2)
				(max_length 1)
				(best_width_ratio 0.9)
				(max_width 2)
				(curved_edges yes)
				(filter_ratio 0.9)
				(enabled yes)
				(allow_two_segments yes)
				(prefer_zone_connections yes)
			)
		)
		(pad "10" smd rect
			(at -2.64 2.22 90)
			(size 0.42 1.12)
			(layers "F.Cu" "F.Mask" "F.Paste")
			(net 596 "/Misc/PWM2")
			(pinfunction "PWM2")
			(pintype "open_collector")
			(teardrops
				(best_length_ratio 0.2)
				(max_length 1)
				(best_width_ratio 0.9)
				(max_width 2)
				(curved_edges yes)
				(filter_ratio 0.9)
				(enabled yes)
				(allow_two_segments yes)
				(prefer_zone_connections yes)
			)
		)
		(pad "11" smd rect
			(at -2.64 2.86 90)
			(size 0.42 1.12)
			(layers "F.Cu" "F.Mask" "F.Paste")
			(net 780 "/Misc/TACH_{A3V3}")
			(pinfunction "TACH1")
			(pintype "input")
			(teardrops
				(best_length_ratio 0.2)
				(max_length 1)
				(best_width_ratio 0.9)
				(max_width 2)
				(curved_edges yes)
				(filter_ratio 0.9)
				(enabled yes)
				(allow_two_segments yes)
				(prefer_zone_connections yes)
			)
		)
		(pad "12" smd rect
			(at -2.64 3.49 90)
			(size 0.42 1.12)
			(layers "F.Cu" "F.Mask" "F.Paste")
			(net 781 "/Misc/TACH_{B3V3}")
			(pinfunction "TACH2")
			(pintype "input")
			(teardrops
				(best_length_ratio 0.2)
				(max_length 1)
				(best_width_ratio 0.9)
				(max_width 2)
				(curved_edges yes)
				(filter_ratio 0.9)
				(enabled yes)
				(allow_two_segments yes)
				(prefer_zone_connections yes)
			)
		)
		(pad "13" smd rect
			(at 2.64 3.49 90)
			(size 0.42 1.12)
			(layers "F.Cu" "F.Mask" "F.Paste")
			(net 588 "/Misc/~{ADDREN}")
			(pinfunction "PWM3")
			(pintype "input")
			(teardrops
				(best_length_ratio 0.2)
				(max_length 1)
				(best_width_ratio 0.9)
				(max_width 2)
				(curved_edges yes)
				(filter_ratio 0.9)
				(enabled yes)
				(allow_two_segments yes)
				(prefer_zone_connections yes)
			)
		)
		(pad "14" smd rect
			(at 2.64 2.86 90)
			(size 0.42 1.12)
			(layers "F.Cu" "F.Mask" "F.Paste")
			(net 589 "/Misc/~{ADDRSEL}")
			(pinfunction "TACH4")
			(pintype "input")
			(teardrops
				(best_length_ratio 0.2)
				(max_length 1)
				(best_width_ratio 0.9)
				(max_width 2)
				(curved_edges yes)
				(filter_ratio 0.9)
				(enabled yes)
				(allow_two_segments yes)
				(prefer_zone_connections yes)
			)
		)
		(pad "15" smd rect
			(at 2.64 2.22 90)
			(size 0.42 1.12)
			(layers "F.Cu" "F.Mask" "F.Paste")
			(net 542 "Net-(Q9-E)")
			(pinfunction "D2-")
			(pintype "passive")
			(teardrops
				(best_length_ratio 0.2)
				(max_length 1)
				(best_width_ratio 0.9)
				(max_width 2)
				(curved_edges yes)
				(filter_ratio 0.9)
				(enabled yes)
				(allow_two_segments yes)
				(prefer_zone_connections yes)
			)
		)
		(pad "16" smd rect
			(at 2.64 1.59 90)
			(size 0.42 1.12)
			(layers "F.Cu" "F.Mask" "F.Paste")
			(net 541 "Net-(Q9-B)")
			(pinfunction "D2+")
			(pintype "passive")
			(teardrops
				(best_length_ratio 0.2)
				(max_length 1)
				(best_width_ratio 0.9)
				(max_width 2)
				(curved_edges yes)
				(filter_ratio 0.9)
				(enabled yes)
				(allow_two_segments yes)
				(prefer_zone_connections yes)
			)
		)
		(pad "17" smd rect
			(at 2.64 0.95 90)
			(size 0.42 1.12)
			(layers "F.Cu" "F.Mask" "F.Paste")
			(net 544 "Net-(Q10-E)")
			(pinfunction "D1-")
			(pintype "passive")
			(teardrops
				(best_length_ratio 0.2)
				(max_length 1)
				(best_width_ratio 0.9)
				(max_width 2)
				(curved_edges yes)
				(filter_ratio 0.9)
				(enabled yes)
				(allow_two_segments yes)
				(prefer_zone_connections yes)
			)
		)
		(pad "18" smd rect
			(at 2.64 0.32 90)
			(size 0.42 1.12)
			(layers "F.Cu" "F.Mask" "F.Paste")
			(net 543 "Net-(Q10-B)")
			(pinfunction "D1+")
			(pintype "passive")
			(teardrops
				(best_length_ratio 0.2)
				(max_length 1)
				(best_width_ratio 0.9)
				(max_width 2)
				(curved_edges yes)
				(filter_ratio 0.9)
				(enabled yes)
				(allow_two_segments yes)
				(prefer_zone_connections yes)
			)
		)
		(pad "19" smd rect
			(at 2.64 -0.32 90)
			(size 0.42 1.12)
			(layers "F.Cu" "F.Mask" "F.Paste")
			(net 594 "Net-(U24-GPIO4)")
			(pinfunction "GPIO4")
			(pintype "open_collector")
			(teardrops
				(best_length_ratio 0.2)
				(max_length 1)
				(best_width_ratio 0.9)
				(max_width 2)
				(curved_edges yes)
				(filter_ratio 0.9)
				(enabled yes)
				(allow_two_segments yes)
				(prefer_zone_connections yes)
			)
		)
		(pad "20" smd rect
			(at 2.64 -0.95 90)
			(size 0.42 1.12)
			(layers "F.Cu" "F.Mask" "F.Paste")
			(net 592 "Net-(U24-+5V_{IN})")
			(pinfunction "+5V_{IN}")
			(pintype "passive")
			(teardrops
				(best_length_ratio 0.2)
				(max_length 1)
				(best_width_ratio 0.9)
				(max_width 2)
				(curved_edges yes)
				(filter_ratio 0.9)
				(enabled yes)
				(allow_two_segments yes)
				(prefer_zone_connections yes)
			)
		)
		(pad "21" smd rect
			(at 2.64 -1.59 90)
			(size 0.42 1.12)
			(layers "F.Cu" "F.Mask" "F.Paste")
			(net 591 "Net-(U24-+12V_{IN})")
			(pinfunction "+12V_{IN}")
			(pintype "passive")
			(teardrops
				(best_length_ratio 0.2)
				(max_length 1)
				(best_width_ratio 0.9)
				(max_width 2)
				(curved_edges yes)
				(filter_ratio 0.9)
				(enabled yes)
				(allow_two_segments yes)
				(prefer_zone_connections yes)
			)
		)
		(pad "22" smd rect
			(at 2.64 -2.22 90)
			(size 0.42 1.12)
			(layers "F.Cu" "F.Mask" "F.Paste")
			(net 590 "Net-(U24-+2.5V_{IN})")
			(pinfunction "+2.5V_{IN}")
			(pintype "passive")
			(teardrops
				(best_length_ratio 0.2)
				(max_length 1)
				(best_width_ratio 0.9)
				(max_width 2)
				(curved_edges yes)
				(filter_ratio 0.9)
				(enabled yes)
				(allow_two_segments yes)
				(prefer_zone_connections yes)
			)
		)
		(pad "23" smd rect
			(at 2.64 -2.86 90)
			(size 0.42 1.12)
			(layers "F.Cu" "F.Mask" "F.Paste")
			(net 593 "Net-(U24-V_{CCP})")
			(pinfunction "V_{CCP}")
			(pintype "passive")
			(teardrops
				(best_length_ratio 0.2)
				(max_length 1)
				(best_width_ratio 0.9)
				(max_width 2)
				(curved_edges yes)
				(filter_ratio 0.9)
				(enabled yes)
				(allow_two_segments yes)
				(prefer_zone_connections yes)
			)
		)
		(pad "24" smd rect
			(at 2.64 -3.49 90)
			(size 0.42 1.12)
			(layers "F.Cu" "F.Mask" "F.Paste")
			(net 597 "/Misc/PWM1")
			(pinfunction "PWM1")
			(pintype "open_collector")
			(teardrops
				(best_length_ratio 0.2)
				(max_length 1)
				(best_width_ratio 0.9)
				(max_width 2)
				(curved_edges yes)
				(filter_ratio 0.9)
				(enabled yes)
				(allow_two_segments yes)
				(prefer_zone_connections yes)
			)
		)
	)
	(footprint "antmicro-footprints:C_0402_1005Metric"
		(layer "F.Cu")
		(at 115.9 146.301 90)
		(descr "Capacitor SMD 0402")
		(tags "capacitor SMD 0402")
		(property "Reference" "C114"
			(at 10.541 2.1 90)
			(layer "F.SilkS")
			(effects
				(font
					(size 0.7 0.7)
					(thickness 0.15)
				)
				(justify left bottom)
			)
		)
		(property "Value" "C_100n_0402"
			(at -1.022927 2.155213 90)
			(layer "F.Fab")
			(effects
				(font
					(size 0.7 0.7)
					(thickness 0.15)
				)
				(justify left bottom)
			)
		)
		(property "Datasheet" "https://www.murata.com/products/productdetail?partno=GRM155R61H104KE14%23"
			(at 0 0 90)
			(layer "F.Fab")
			(hide yes)
			(effects
				(font
					(size 1.27 1.27)
					(thickness 0.15)
				)
			)
		)
		(property "Author" "Antmicro"
			(at 262.201 30.401 0)
			(layer "F.Fab")
			(hide yes)
			(effects
				(font
					(size 1 1)
					(thickness 0.15)
				)
			)
		)
		(property "Dielectric" "X5R"
			(at 262.201 30.401 0)
			(layer "F.Fab")
			(hide yes)
			(effects
				(font
					(size 1 1)
					(thickness 0.15)
				)
			)
		)
		(property "License" "Apache-2.0"
			(at 262.201 30.401 0)
			(layer "F.Fab")
			(hide yes)
			(effects
				(font
					(size 1 1)
					(thickness 0.15)
				)
			)
		)
		(property "MPN" "GRM155R61H104KE14D"
			(at 262.201 30.401 0)
			(layer "F.Fab")
			(hide yes)
			(effects
				(font
					(size 1 1)
					(thickness 0.15)
				)
			)
		)
		(property "Manufacturer" "Murata"
			(at 262.201 30.401 0)
			(layer "F.Fab")
			(hide yes)
			(effects
				(font
					(size 1 1)
					(thickness 0.15)
				)
			)
		)
		(property "Public" "False"
			(at 262.201 30.401 0)
			(layer "F.Fab")
			(hide yes)
			(effects
				(font
					(size 1 1)
					(thickness 0.15)
				)
			)
		)
		(property "Val" "100n"
			(at 262.201 30.401 0)
			(layer "F.Fab")
			(hide yes)
			(effects
				(font
					(size 1 1)
					(thickness 0.15)
				)
			)
		)
		(property "Voltage" "50V"
			(at 262.201 30.401 0)
			(layer "F.Fab")
			(hide yes)
			(effects
				(font
					(size 1 1)
					(thickness 0.15)
				)
			)
		)
		(sheetname "PCIe redriver")
		(sheetfile "pcie_redriver.kicad_sch")
		(attr smd)
		(fp_rect
			(start -0.925 -0.47)
			(end 0.925 0.47)
			(stroke
				(width 0.05)
				(type default)
			)
			(fill no)
			(layer "F.CrtYd")
		)
		(fp_line
			(start 0.504 -0.25)
			(end 0.504 0.248)
			(stroke
				(width 0.15)
				(type solid)
			)
			(layer "F.Fab")
		)
		(fp_line
			(start -0.494 -0.25)
			(end 0.504 -0.25)
			(stroke
				(width 0.15)
				(type solid)
			)
			(layer "F.Fab")
		)
		(fp_line
			(start 0.504 0.248)
			(end -0.494 0.248)
			(stroke
				(width 0.15)
				(type solid)
			)
			(layer "F.Fab")
		)
		(fp_line
			(start -0.494 0.248)
			(end -0.494 -0.25)
			(stroke
				(width 0.15)
				(type solid)
			)
			(layer "F.Fab")
		)
		(pad "1" smd roundrect
			(at -0.48 0 90)
			(size 0.59 0.64)
			(layers "F.Cu" "F.Mask" "F.Paste")
			(roundrect_rratio 0.25)
			(net 1 "GND")
			(pintype "passive")
			(teardrops
				(best_length_ratio 0.2)
				(max_length 1)
				(best_width_ratio 0.9)
				(max_width 2)
				(curved_edges yes)
				(filter_ratio 0.9)
				(enabled yes)
				(allow_two_segments yes)
				(prefer_zone_connections yes)
			)
		)
		(pad "2" smd roundrect
			(at 0.48 0 90)
			(size 0.59 0.64)
			(layers "F.Cu" "F.Mask" "F.Paste")
			(roundrect_rratio 0.25)
			(net 2 "+3V3")
			(pintype "passive")
			(teardrops
				(best_length_ratio 0.2)
				(max_length 1)
				(best_width_ratio 0.9)
				(max_width 2)
				(curved_edges yes)
				(filter_ratio 0.9)
				(enabled yes)
				(allow_two_segments yes)
				(prefer_zone_connections yes)
			)
		)
	)
	(footprint "antmicro-footprints:TP_SMD_0.75mm"
		(layer "F.Cu")
		(at 183.70861 72.802163 -90)
		(property "Reference" "TP105"
			(at 0 -0.6 90)
			(layer "F.SilkS")
			(hide yes)
			(effects
				(font
					(size 0.7 0.7)
					(thickness 0.15)
				)
				(justify right bottom)
			)
		)
		(property "Value" "TP_0.75mm_SMD"
			(at 0 1.2 90)
			(layer "F.Fab")
			(effects
				(font
					(size 0.7 0.7)
					(thickness 0.15)
				)
				(justify right bottom)
			)
		)
		(property "Author" "Antmicro"
			(at 110.906447 256.510773 0)
			(layer "F.Fab")
			(hide yes)
			(effects
				(font
					(size 1 1)
					(thickness 0.15)
				)
			)
		)
		(property "License" "Apache-2.0"
			(at 110.906447 256.510773 0)
			(layer "F.Fab")
			(hide yes)
			(effects
				(font
					(size 1 1)
					(thickness 0.15)
				)
			)
		)
		(property "MPN" ""
			(at 110.906447 256.510773 0)
			(layer "F.Fab")
			(hide yes)
			(effects
				(font
					(size 1 1)
					(thickness 0.15)
				)
			)
		)
		(property "Manufacturer" ""
			(at 110.906447 256.510773 0)
			(layer "F.Fab")
			(hide yes)
			(effects
				(font
					(size 1 1)
					(thickness 0.15)
				)
			)
		)
		(property "Public" "False"
			(at 110.906447 256.510773 0)
			(layer "F.Fab")
			(hide yes)
			(effects
				(font
					(size 1 1)
					(thickness 0.15)
				)
			)
		)
		(sheetname "Power")
		(sheetfile "power.kicad_sch")
		(attr exclude_from_pos_files exclude_from_bom)
		(fp_circle
			(center 0 0)
			(end 0.475 0)
			(stroke
				(width 0.05)
				(type default)
			)
			(fill no)
			(layer "F.CrtYd")
		)
		(pad "1" smd circle
			(at 0 0 270)
			(size 0.75 0.75)
			(layers "F.Cu" "F.Mask")
			(net 1 "GND")
			(pinfunction "1")
			(pintype "passive")
			(teardrops
				(best_length_ratio 0.4)
				(max_length 1)
				(best_width_ratio 0.9)
				(max_width 2)
				(curved_edges yes)
				(filter_ratio 0.9)
				(enabled yes)
				(allow_two_segments yes)
				(prefer_zone_connections yes)
			)
		)
	)
)
